(kicad_pcb
	(version 20241229)
	(generator "pcbnew")
	(generator_version "9.0")
	(general
		(thickness 1.294)
		(legacy_teardrops no)
	)
	(paper "A3")
	(title_block
		(title "Kintex 410T devboard")
		(date "2024-04-03")
		(rev "1.1.2")
		(comment 9 "footprints 33-38 of 975")
	)
	(layers
		(0 "F.Cu" mixed)
		(4 "In1.Cu" power)
		(6 "In2.Cu" power)
		(8 "In3.Cu" mixed)
		(10 "In4.Cu" power)
		(12 "In5.Cu" mixed)
		(14 "In6.Cu" power)
		(16 "In7.Cu" mixed)
		(18 "In8.Cu" power)
		(2 "B.Cu" mixed)
		(9 "F.Adhes" user "F.Adhesive")
		(11 "B.Adhes" user "B.Adhesive")
		(13 "F.Paste" user)
		(15 "B.Paste" user)
		(5 "F.SilkS" user "F.Silkscreen")
		(7 "B.SilkS" user "B.Silkscreen")
		(1 "F.Mask" user)
		(3 "B.Mask" user)
		(17 "Dwgs.User" user "User.Drawings")
		(19 "Cmts.User" user "User.Comments")
		(21 "Eco1.User" user "User.Eco1")
		(23 "Eco2.User" user "User.Eco2")
		(25 "Edge.Cuts" user)
		(27 "Margin" user)
		(31 "F.CrtYd" user "F.Courtyard")
		(29 "B.CrtYd" user "B.Courtyard")
		(35 "F.Fab" user)
		(33 "B.Fab" user)
	)
	(footprint "antmicro-footprints:R_0402_1005Metric"
		(layer "F.Cu")
		(at 244.15 107.8)
		(descr "Resistor SMD 0402")
		(tags "resistor SMD 0402")
		(property "Reference" "R258"
			(at 0.8 0.35 0)
			(layer "F.SilkS")
			(effects
				(font
					(size 0.7 0.7)
					(thickness 0.15)
				)
				(justify left bottom)
			)
		)
		(property "Value" "R_0R_0402"
			(at 0 1.4 0)
			(layer "F.Fab")
			(effects
				(font
					(size 0.7 0.7)
					(thickness 0.15)
				)
				(justify left bottom)
			)
		)
		(property "Description" "SMD Chip Resistor, Jumper, 0 ohm, 100 mW, 0402 [1005 Metric], Thick Film, General Purpose"
			(at 0 0 0)
			(layer "F.Fab")
			(hide yes)
			(effects
				(font
					(size 1.27 1.27)
					(thickness 0.15)
				)
			)
		)
		(property "Author" "Antmicro"
			(at 0 0 0)
			(layer "F.Fab")
			(hide yes)
			(effects
				(font
					(size 1 1)
					(thickness 0.15)
				)
			)
		)
		(property "Current" "1A"
			(at 0 0 0)
			(layer "F.Fab")
			(hide yes)
			(effects
				(font
					(size 1 1)
					(thickness 0.15)
				)
			)
		)
		(property "License" "Apache-2.0"
			(at 0 0 0)
			(layer "F.Fab")
			(hide yes)
			(effects
				(font
					(size 1 1)
					(thickness 0.15)
				)
			)
		)
		(property "MPN" "ERJ2GE0R00X"
			(at 0 0 0)
			(layer "F.Fab")
			(hide yes)
			(effects
				(font
					(size 1 1)
					(thickness 0.15)
				)
			)
		)
		(property "Manufacturer" "Panasonic"
			(at 0 0 0)
			(layer "F.Fab")
			(hide yes)
			(effects
				(font
					(size 1 1)
					(thickness 0.15)
				)
			)
		)
		(property "Tolerance" ""
			(at 0 0 0)
			(layer "F.Fab")
			(hide yes)
			(effects
				(font
					(size 1 1)
					(thickness 0.15)
				)
			)
		)
		(property "Val" "0R"
			(at 0 0 0)
			(layer "F.Fab")
			(hide yes)
			(effects
				(font
					(size 1 1)
					(thickness 0.15)
				)
			)
		)
		(sheetname "HDMI + Ethernet")
		(sheetfile "hdmi-ethernet.kicad_sch")
		(attr smd)
		(fp_rect
			(start -0.925 -0.47)
			(end 0.925 0.47)
			(stroke
				(width 0.05)
				(type default)
			)
			(fill no)
			(layer "F.CrtYd")
		)
		(fp_rect
			(start -0.5 -0.25)
			(end 0.5 0.25)
			(stroke
				(width 0.15)
				(type solid)
			)
			(fill no)
			(layer "F.Fab")
		)
		(pad "1" smd roundrect
			(at -0.48 0)
			(size 0.59 0.64)
			(layers "F.Cu" "F.Mask" "F.Paste")
			(roundrect_rratio 0.25)
			(net 528 "/FPGA Bank 16 & 17/HDMI.D0_P")
			(pintype "passive")
		)
		(pad "2" smd roundrect
			(at 0.48 0)
			(size 0.59 0.64)
			(layers "F.Cu" "F.Mask" "F.Paste")
			(roundrect_rratio 0.25)
			(net 863 "/HDMI + Ethernet/HDMI_CONN_D0_P")
			(pintype "passive")
		)
	)
	(footprint "antmicro-footprints:R_0402_1005Metric"
		(layer "F.Cu")
		(at 172.75 175.7125 180)
		(descr "Resistor SMD 0402")
		(tags "resistor SMD 0402")
		(property "Reference" "R315"
			(at 1.25 -1.2875 180)
			(layer "F.SilkS")
			(effects
				(font
					(size 0.7 0.7)
					(thickness 0.15)
				)
				(justify left bottom)
			)
		)
		(property "Value" "R_0R_0402"
			(at 0 1.4 180)
			(layer "F.Fab")
			(effects
				(font
					(size 0.7 0.7)
					(thickness 0.15)
				)
				(justify left bottom)
			)
		)
		(property "Description" "SMD Chip Resistor, Jumper, 0 ohm, 100 mW, 0402 [1005 Metric], Thick Film, General Purpose"
			(at 0 0 180)
			(layer "F.Fab")
			(hide yes)
			(effects
				(font
					(size 1.27 1.27)
					(thickness 0.15)
				)
			)
		)
		(property "Author" "Antmicro"
			(at 345.5 351.425 0)
			(layer "F.Fab")
			(hide yes)
			(effects
				(font
					(size 1 1)
					(thickness 0.15)
				)
			)
		)
		(property "Current" "1A"
			(at 345.5 351.425 0)
			(layer "F.Fab")
			(hide yes)
			(effects
				(font
					(size 1 1)
					(thickness 0.15)
				)
			)
		)
		(property "License" "Apache-2.0"
			(at 345.5 351.425 0)
			(layer "F.Fab")
			(hide yes)
			(effects
				(font
					(size 1 1)
					(thickness 0.15)
				)
			)
		)
		(property "MPN" "ERJ2GE0R00X"
			(at 345.5 351.425 0)
			(layer "F.Fab")
			(hide yes)
			(effects
				(font
					(size 1 1)
					(thickness 0.15)
				)
			)
		)
		(property "Manufacturer" "Panasonic"
			(at 345.5 351.425 0)
			(layer "F.Fab")
			(hide yes)
			(effects
				(font
					(size 1 1)
					(thickness 0.15)
				)
			)
		)
		(property "Tolerance" ""
			(at 345.5 351.425 0)
			(layer "F.Fab")
			(hide yes)
			(effects
				(font
					(size 1 1)
					(thickness 0.15)
				)
			)
		)
		(property "Val" "0R"
			(at 345.5 351.425 0)
			(layer "F.Fab")
			(hide yes)
			(effects
				(font
					(size 1 1)
					(thickness 0.15)
				)
			)
		)
		(sheetname "DC-DC Converters")
		(sheetfile "dc-dc.kicad_sch")
		(attr smd)
		(fp_rect
			(start -0.925 -0.47)
			(end 0.925 0.47)
			(stroke
				(width 0.05)
				(type default)
			)
			(fill no)
			(layer "F.CrtYd")
		)
		(fp_rect
			(start -0.5 -0.25)
			(end 0.5 0.25)
			(stroke
				(width 0.15)
				(type solid)
			)
			(fill no)
			(layer "F.Fab")
		)
		(pad "1" smd roundrect
			(at -0.48 0 180)
			(size 0.59 0.64)
			(layers "F.Cu" "F.Mask" "F.Paste")
			(roundrect_rratio 0.25)
			(net 965 "/DC-DC Converters/FB8")
			(pintype "passive")
		)
		(pad "2" smd roundrect
			(at 0.48 0 180)
			(size 0.59 0.64)
			(layers "F.Cu" "F.Mask" "F.Paste")
			(roundrect_rratio 0.25)
			(net 740 "/DC-DC Converters/1V35_local")
			(pintype "passive")
		)
	)
	(footprint "antmicro-footprints:NetTie-2_SMD_Pad0.127mm"
		(layer "F.Cu")
		(at 240.4 128.373 -90)
		(descr "Net tie, 2 pin, 0.127mm  SMD pads")
		(tags "net tie")
		(property "Reference" "NT18"
			(at -0.128 -1.345 270)
			(layer "F.SilkS")
			(hide yes)
			(effects
				(font
					(size 0.7 0.7)
					(thickness 0.15)
				)
				(justify left bottom)
			)
		)
		(property "Value" "Net-Tie_2"
			(at 0 1.199 270)
			(layer "F.Fab")
			(effects
				(font
					(size 0.7 0.7)
					(thickness 0.15)
				)
				(justify left bottom)
			)
		)
		(property "Description" "Net tie, 2 pins"
			(at 0 0 270)
			(layer "F.Fab")
			(hide yes)
			(effects
				(font
					(size 1.27 1.27)
					(thickness 0.15)
				)
			)
		)
		(property "Author" "Antmicro"
			(at 112.027 368.773 0)
			(layer "F.Fab")
			(hide yes)
			(effects
				(font
					(size 1 1)
					(thickness 0.15)
				)
			)
		)
		(property "License" "Apache-2.0"
			(at 112.027 368.773 0)
			(layer "F.Fab")
			(hide yes)
			(effects
				(font
					(size 1 1)
					(thickness 0.15)
				)
			)
		)
		(property "MPN" ""
			(at 112.027 368.773 0)
			(layer "F.Fab")
			(hide yes)
			(effects
				(font
					(size 1 1)
					(thickness 0.15)
				)
			)
		)
		(property "Manufacturer" ""
			(at 112.027 368.773 0)
			(layer "F.Fab")
			(hide yes)
			(effects
				(font
					(size 1 1)
					(thickness 0.15)
				)
			)
		)
		(sheetname "FPGA Bank 12 & 13")
		(sheetfile "fpga-bank-12-13.kicad_sch")
		(attr exclude_from_pos_files)
		(net_tie_pad_groups "1, 2")
		(fp_poly
			(pts
				(xy -0.0635 -0.0635) (xy 0.0625 -0.0635) (xy 0.0625 0.0635) (xy -0.0635 0.0635)
			)
			(stroke
				(width 0)
				(type solid)
			)
			(fill yes)
			(layer "F.Cu")
		)
		(pad "1" smd roundrect
			(at -0.127 0 90)
			(size 0.127 0.127)
			(layers "F.Cu")
			(roundrect_rratio 0.5)
			(chamfer_ratio 0)
			(chamfer top_left bottom_left)
			(net 1331 "/SUP_MCU.RX0")
			(pinfunction "1")
			(pintype "passive")
		)
		(pad "2" smd roundrect
			(at 0.126 0 270)
			(size 0.127 0.127)
			(layers "F.Cu")
			(roundrect_rratio 0.5)
			(chamfer_ratio 0)
			(chamfer top_left bottom_left)
			(net 55 "/FPGA Bank 12 & 13/UART0.TX")
			(pinfunction "2")
			(pintype "passive")
		)
	)
	(footprint "antmicro-footprints:C_0402_1005Metric"
		(layer "F.Cu")
		(at 158.85 153.75 90)
		(descr "Capacitor SMD 0402")
		(tags "capacitor SMD 0402")
		(property "Reference" "C358"
			(at 0.8 0.35 90)
			(layer "F.SilkS")
			(effects
				(font
					(size 0.7 0.7)
					(thickness 0.15)
				)
				(justify left bottom)
			)
		)
		(property "Value" "C_10u_0402"
			(at 0 1.4 90)
			(layer "F.Fab")
			(effects
				(font
					(size 0.7 0.7)
					(thickness 0.15)
				)
				(justify left bottom)
			)
		)
		(property "Description" "SMD Multilayer Ceramic Capacitor, 10 µF, 6.3 V, 0402 [1005 Metric], ± 20%, X5R, CC Series"
			(at 0 0 90)
			(layer "F.Fab")
			(hide yes)
			(effects
				(font
					(size 1.27 1.27)
					(thickness 0.15)
				)
			)
		)
		(property "Author" "Antmicro"
			(at 312.6 -5.1 0)
			(layer "F.Fab")
			(hide yes)
			(effects
				(font
					(size 1 1)
					(thickness 0.15)
				)
			)
		)
		(property "Dielectric" ""
			(at 312.6 -5.1 0)
			(layer "F.Fab")
			(hide yes)
			(effects
				(font
					(size 1 1)
					(thickness 0.15)
				)
			)
		)
		(property "License" "Apache-2.0"
			(at 312.6 -5.1 0)
			(layer "F.Fab")
			(hide yes)
			(effects
				(font
					(size 1 1)
					(thickness 0.15)
				)
			)
		)
		(property "MPN" "CC0402MRX5R5BB106"
			(at 312.6 -5.1 0)
			(layer "F.Fab")
			(hide yes)
			(effects
				(font
					(size 1 1)
					(thickness 0.15)
				)
			)
		)
		(property "Manufacturer" "YAGEO"
			(at 312.6 -5.1 0)
			(layer "F.Fab")
			(hide yes)
			(effects
				(font
					(size 1 1)
					(thickness 0.15)
				)
			)
		)
		(property "Val" "10u"
			(at 312.6 -5.1 0)
			(layer "F.Fab")
			(hide yes)
			(effects
				(font
					(size 1 1)
					(thickness 0.15)
				)
			)
		)
		(property "Voltage" ""
			(at 312.6 -5.1 0)
			(layer "F.Fab")
			(hide yes)
			(effects
				(font
					(size 1 1)
					(thickness 0.15)
				)
			)
		)
		(sheetname "DC-DC Converters")
		(sheetfile "dc-dc.kicad_sch")
		(attr smd)
		(fp_rect
			(start -0.925 -0.47)
			(end 0.925 0.47)
			(stroke
				(width 0.05)
				(type default)
			)
			(fill no)
			(layer "F.CrtYd")
		)
		(fp_line
			(start 0.504 -0.25)
			(end 0.504 0.248)
			(stroke
				(width 0.15)
				(type solid)
			)
			(layer "F.Fab")
		)
		(fp_line
			(start -0.494 -0.25)
			(end 0.504 -0.25)
			(stroke
				(width 0.15)
				(type solid)
			)
			(layer "F.Fab")
		)
		(fp_line
			(start 0.504 0.248)
			(end -0.494 0.248)
			(stroke
				(width 0.15)
				(type solid)
			)
			(layer "F.Fab")
		)
		(fp_line
			(start -0.494 0.248)
			(end -0.494 -0.25)
			(stroke
				(width 0.15)
				(type solid)
			)
			(layer "F.Fab")
		)
		(pad "1" smd roundrect
			(at -0.48 0 90)
			(size 0.59 0.64)
			(layers "F.Cu" "F.Mask" "F.Paste")
			(roundrect_rratio 0.25)
			(net 1 "GND")
			(pintype "passive")
		)
		(pad "2" smd roundrect
			(at 0.48 0 90)
			(size 0.59 0.64)
			(layers "F.Cu" "F.Mask" "F.Paste")
			(roundrect_rratio 0.25)
			(net 750 "/DC-DC Converters/VDDR_VTT")
			(pintype "passive")
		)
	)
	(footprint "antmicro-footprints:C_2220_5650Metric"
		(layer "F.Cu")
		(at 240.275 185.575 90)
		(descr "Capacitor SMD 2220")
		(tags "capacitor SMD 2220")
		(property "Reference" "C196"
			(at 3.675 -1.425 180)
			(layer "F.SilkS")
			(effects
				(font
					(size 0.7 0.7)
					(thickness 0.15)
				)
				(justify left bottom)
			)
		)
		(property "Value" "C_22u_100V_2220"
			(at 0 3.9 90)
			(layer "F.Fab")
			(effects
				(font
					(size 0.7 0.7)
					(thickness 0.15)
				)
				(justify left bottom)
			)
		)
		(property "Description" "SMT Multilayer Ceramic Capacitor, 22 µF, 100 V, 2220 [5750 Metric], ± 20%, X7S, C"
			(at 0 0 90)
			(layer "F.Fab")
			(hide yes)
			(effects
				(font
					(size 1.27 1.27)
					(thickness 0.15)
				)
			)
		)
		(property "Author" "Antmicro"
			(at 425.85 -54.7 0)
			(layer "F.Fab")
			(hide yes)
			(effects
				(font
					(size 1 1)
					(thickness 0.15)
				)
			)
		)
		(property "Dielectric" "X7S"
			(at 425.85 -54.7 0)
			(layer "F.Fab")
			(hide yes)
			(effects
				(font
					(size 1 1)
					(thickness 0.15)
				)
			)
		)
		(property "License" "Apache-2.0"
			(at 425.85 -54.7 0)
			(layer "F.Fab")
			(hide yes)
			(effects
				(font
					(size 1 1)
					(thickness 0.15)
				)
			)
		)
		(property "MPN" "C5750X7S2A226M280KB"
			(at 425.85 -54.7 0)
			(layer "F.Fab")
			(hide yes)
			(effects
				(font
					(size 1 1)
					(thickness 0.15)
				)
			)
		)
		(property "Manufacturer" "TDK"
			(at 425.85 -54.7 0)
			(layer "F.Fab")
			(hide yes)
			(effects
				(font
					(size 1 1)
					(thickness 0.15)
				)
			)
		)
		(property "Val" "22u"
			(at 425.85 -54.7 0)
			(layer "F.Fab")
			(hide yes)
			(effects
				(font
					(size 1 1)
					(thickness 0.15)
				)
			)
		)
		(property "Voltage" "100V"
			(at 425.85 -54.7 0)
			(layer "F.Fab")
			(hide yes)
			(effects
				(font
					(size 1 1)
					(thickness 0.15)
				)
			)
		)
		(sheetname "Power supply")
		(sheetfile "power-supply.kicad_sch")
		(attr smd)
		(fp_line
			(start -1.415 -2.61)
			(end 1.415 -2.61)
			(stroke
				(width 0.15)
				(type solid)
			)
			(layer "F.SilkS")
		)
		(fp_line
			(start -1.415 2.61)
			(end 1.415 2.61)
			(stroke
				(width 0.15)
				(type solid)
			)
			(layer "F.SilkS")
		)
		(fp_rect
			(start -3.7 -2.95)
			(end 3.7 2.95)
			(stroke
				(width 0.05)
				(type solid)
			)
			(fill no)
			(layer "F.CrtYd")
		)
		(fp_rect
			(start -2.85 -2.5)
			(end 2.85 2.5)
			(stroke
				(width 0.15)
				(type solid)
			)
			(fill no)
			(layer "F.Fab")
		)
		(pad "1" smd roundrect
			(at -2.55 0 90)
			(size 1.8 5.4)
			(layers "F.Cu" "F.Mask" "F.Paste")
			(roundrect_rratio 0.138889)
			(net 699 "GNDD")
			(pintype "passive")
		)
		(pad "2" smd roundrect
			(at 2.55 0 90)
			(size 1.8 5.4)
			(layers "F.Cu" "F.Mask" "F.Paste")
			(roundrect_rratio 0.138889)
			(net 698 "/Power supply/VDD")
			(pintype "passive")
		)
	)
	(footprint "antmicro-footprints:C_0402_1005Metric"
		(layer "F.Cu")
		(at 156.225 158)
		(descr "Capacitor SMD 0402")
		(tags "capacitor SMD 0402")
		(property "Reference" "C350"
			(at -1.874 2.35 0)
			(layer "F.SilkS")
			(effects
				(font
					(size 0.7 0.7)
					(thickness 0.15)
				)
				(justify left bottom)
			)
		)
		(property "Value" "C_1n_0402"
			(at 0 1.4 0)
			(layer "F.Fab")
			(effects
				(font
					(size 0.7 0.7)
					(thickness 0.15)
				)
				(justify left bottom)
			)
		)
		(property "Description" "SMD Multilayer Ceramic Capacitor, 1000 pF, 50 V, 0402 [1005 Metric], ± 5%, C0G / NP0, GRM Series"
			(at 0 0 0)
			(layer "F.Fab")
			(hide yes)
			(effects
				(font
					(size 1.27 1.27)
					(thickness 0.15)
				)
			)
		)
		(property "Author" "Antmicro"
			(at 0 0 0)
			(layer "F.Fab")
			(hide yes)
			(effects
				(font
					(size 1 1)
					(thickness 0.15)
				)
			)
		)
		(property "Dielectric" "C0G"
			(at 0 0 0)
			(layer "F.Fab")
			(hide yes)
			(effects
				(font
					(size 1 1)
					(thickness 0.15)
				)
			)
		)
		(property "License" "Apache-2.0"
			(at 0 0 0)
			(layer "F.Fab")
			(hide yes)
			(effects
				(font
					(size 1 1)
					(thickness 0.15)
				)
			)
		)
		(property "MPN" "GRM1555C1H102JA01D"
			(at 0 0 0)
			(layer "F.Fab")
			(hide yes)
			(effects
				(font
					(size 1 1)
					(thickness 0.15)
				)
			)
		)
		(property "Manufacturer" "Murata"
			(at 0 0 0)
			(layer "F.Fab")
			(hide yes)
			(effects
				(font
					(size 1 1)
					(thickness 0.15)
				)
			)
		)
		(property "Val" "1n"
			(at 0 0 0)
			(layer "F.Fab")
			(hide yes)
			(effects
				(font
					(size 1 1)
					(thickness 0.15)
				)
			)
		)
		(property "Voltage" "50V"
			(at 0 0 0)
			(layer "F.Fab")
			(hide yes)
			(effects
				(font
					(size 1 1)
					(thickness 0.15)
				)
			)
		)
		(sheetname "DC-DC Converters")
		(sheetfile "dc-dc.kicad_sch")
		(attr smd)
		(fp_rect
			(start -0.925 -0.47)
			(end 0.925 0.47)
			(stroke
				(width 0.05)
				(type default)
			)
			(fill no)
			(layer "F.CrtYd")
		)
		(fp_line
			(start -0.494 -0.25)
			(end 0.504 -0.25)
			(stroke
				(width 0.15)
				(type solid)
			)
			(layer "F.Fab")
		)
		(fp_line
			(start -0.494 0.248)
			(end -0.494 -0.25)
			(stroke
				(width 0.15)
				(type solid)
			)
			(layer "F.Fab")
		)
		(fp_line
			(start 0.504 -0.25)
			(end 0.504 0.248)
			(stroke
				(width 0.15)
				(type solid)
			)
			(layer "F.Fab")
		)
		(fp_line
			(start 0.504 0.248)
			(end -0.494 0.248)
			(stroke
				(width 0.15)
				(type solid)
			)
			(layer "F.Fab")
		)
		(pad "1" smd roundrect
			(at -0.48 0)
			(size 0.59 0.64)
			(layers "F.Cu" "F.Mask" "F.Paste")
			(roundrect_rratio 0.25)
			(net 1 "GND")
			(pintype "passive")
		)
		(pad "2" smd roundrect
			(at 0.48 0)
			(size 0.59 0.64)
			(layers "F.Cu" "F.Mask" "F.Paste")
			(roundrect_rratio 0.25)
			(net 744 "/DC-DC Converters/VDDR_VRI")
			(pintype "passive")
		)
	)
)
